(kicad_pcb
	(version 20241229)
	(generator "pcbnew")
	(generator_version "9.0")
	(general
		(thickness 1.6296)
		(legacy_teardrops no)
	)
	(paper "A3")
	(title_block
		(title "Thunderbolt to 10GbE adapter")
		(date "2026-04-21")
		(rev "1.1.0")
		(company "Antmicro Ltd")
		(comment 1 "www.antmicro.com")
		(comment 9 "footprints 412-415 of 703")
	)
	(layers
		(0 "F.Cu" signal)
		(4 "In1.Cu" signal)
		(6 "In2.Cu" signal)
		(8 "In3.Cu" signal)
		(10 "In4.Cu" signal)
		(12 "In5.Cu" signal)
		(14 "In6.Cu" signal)
		(2 "B.Cu" signal)
		(9 "F.Adhes" user "F.Adhesive")
		(11 "B.Adhes" user "B.Adhesive")
		(13 "F.Paste" user)
		(15 "B.Paste" user)
		(5 "F.SilkS" user "F.Silkscreen")
		(7 "B.SilkS" user "B.Silkscreen")
		(1 "F.Mask" user)
		(3 "B.Mask" user)
		(17 "Dwgs.User" user "User.Drawings")
		(19 "Cmts.User" user "User.Comments")
		(21 "Eco1.User" user "User.Eco1")
		(23 "Eco2.User" user "User.Eco2")
		(25 "Edge.Cuts" user)
		(27 "Margin" user)
		(31 "F.CrtYd" user "F.Courtyard")
		(29 "B.CrtYd" user "B.Courtyard")
		(35 "F.Fab" user)
		(33 "B.Fab" user)
	)
	(footprint "antmicro-footprints:R_0402_1005Metric"
		(layer "B.Cu")
		(at 153.031867 83.185117)
		(descr "Resistor SMD 0402")
		(tags "resistor SMD 0402")
		(property "Reference" "R163"
			(at 20.368136 9.464883 180)
			(layer "B.SilkS")
			(effects
				(font
					(size 0.7 0.7)
					(thickness 0.15)
				)
				(justify mirror)
			)
		)
		(property "Value" "R_1k_0402"
			(at -1.011843 -1.772047 180)
			(layer "B.Fab")
			(effects
				(font
					(size 0.7 0.7)
					(thickness 0.15)
				)
				(justify left bottom mirror)
			)
		)
		(property "Datasheet" "https://www.bourns.com/docs/product-datasheets/cr.pdf"
			(at 0 0 180)
			(layer "B.Fab")
			(hide yes)
			(effects
				(font
					(size 1.27 1.27)
					(thickness 0.15)
				)
				(justify mirror)
			)
		)
		(property "Description" "SMD Chip Resistor, 1 kohm, ± 1%, 63 mW, 0402 [1005 Metric], Thick Film, General Purpose"
			(at 0 0 180)
			(layer "B.Fab")
			(hide yes)
			(effects
				(font
					(size 1.27 1.27)
					(thickness 0.15)
				)
				(justify mirror)
			)
		)
		(property "MPN" "CR0402-FX-1001GLF"
			(at 0 0 0)
			(unlocked yes)
			(layer "B.Fab")
			(hide yes)
			(effects
				(font
					(size 1 1)
					(thickness 0.15)
				)
				(justify mirror)
			)
		)
		(property "Manufacturer" "Bourns"
			(at 0 0 0)
			(unlocked yes)
			(layer "B.Fab")
			(hide yes)
			(effects
				(font
					(size 1 1)
					(thickness 0.15)
				)
				(justify mirror)
			)
		)
		(property "License" "Apache-2.0"
			(at 0 0 0)
			(unlocked yes)
			(layer "B.Fab")
			(hide yes)
			(effects
				(font
					(size 1 1)
					(thickness 0.15)
				)
				(justify mirror)
			)
		)
		(property "Author" "Antmicro"
			(at 0 0 0)
			(unlocked yes)
			(layer "B.Fab")
			(hide yes)
			(effects
				(font
					(size 1 1)
					(thickness 0.15)
				)
				(justify mirror)
			)
		)
		(property "Val" "1k"
			(at 0 0 0)
			(unlocked yes)
			(layer "B.Fab")
			(hide yes)
			(effects
				(font
					(size 1 1)
					(thickness 0.15)
				)
				(justify mirror)
			)
		)
		(property "Tolerance" "1%"
			(at 0 0 0)
			(unlocked yes)
			(layer "B.Fab")
			(hide yes)
			(effects
				(font
					(size 1 1)
					(thickness 0.15)
				)
				(justify mirror)
			)
		)
		(sheetname "/X710-AT2 Misc/")
		(sheetfile "x710-at2-mics.kicad_sch")
		(attr smd)
		(fp_rect
			(start -0.925 0.47)
			(end 0.925 -0.47)
			(stroke
				(width 0.05)
				(type default)
			)
			(fill no)
			(layer "B.CrtYd")
		)
		(fp_rect
			(start -0.5 0.25)
			(end 0.5 -0.25)
			(stroke
				(width 0.15)
				(type solid)
			)
			(fill no)
			(layer "B.Fab")
		)
		(fp_text user "${REFERENCE}"
			(at -0.95 -3.168 180)
			(layer "B.Fab")
			(effects
				(font
					(size 0.7 0.7)
					(thickness 0.15)
				)
				(justify left bottom mirror)
			)
		)
		(fp_text user "Author: Antmicro"
			(at -0.95 -4.169 180)
			(layer "B.Fab")
			(effects
				(font
					(size 0.7 0.7)
					(thickness 0.15)
				)
				(justify left bottom mirror)
			)
		)
		(fp_text user "License: Apache-2.0"
			(at -0.95 -5.169 180)
			(layer "B.Fab")
			(effects
				(font
					(size 0.7 0.7)
					(thickness 0.15)
				)
				(justify left bottom mirror)
			)
		)
		(pad "1" smd roundrect
			(at -0.48 0)
			(size 0.59 0.64)
			(layers "B.Cu" "B.Mask" "B.Paste")
			(roundrect_rratio 0.25)
			(net 23 "GND")
			(pintype "passive")
		)
		(pad "2" smd roundrect
			(at 0.48 0)
			(size 0.59 0.64)
			(layers "B.Cu" "B.Mask" "B.Paste")
			(roundrect_rratio 0.25)
			(net 88 "/X710-AT2 Misc/~{PHY_TRST}")
			(pintype "passive")
		)
	)
	(footprint "antmicro-footprints:Fiducial_1mm_Mask2mm"
		(layer "B.Cu")
		(at 175 47.5 180)
		(descr "Circular Fiducial, 1mm bare copper, 3mm soldermask opening")
		(tags "fiducial")
		(property "Reference" "FD4"
			(at -1 -2.7 0)
			(layer "B.SilkS")
			(effects
				(font
					(size 0.7 0.7)
					(thickness 0.15)
				)
				(justify left bottom mirror)
			)
		)
		(property "Value" "Fiducial_1mm_Mask2mm"
			(at 0 -2.2 0)
			(layer "B.Fab")
			(effects
				(font
					(size 0.7 0.7)
					(thickness 0.15)
				)
				(justify left bottom mirror)
			)
		)
		(property "Description" "Fiducial mask"
			(at 0 0 0)
			(layer "B.Fab")
			(hide yes)
			(effects
				(font
					(size 1.27 1.27)
					(thickness 0.15)
				)
				(justify mirror)
			)
		)
		(property "Author" "Antmicro"
			(at 0 0 180)
			(unlocked yes)
			(layer "B.Fab")
			(hide yes)
			(effects
				(font
					(size 1 1)
					(thickness 0.15)
				)
				(justify mirror)
			)
		)
		(property "License" "Apache-2.0"
			(at 0 0 180)
			(unlocked yes)
			(layer "B.Fab")
			(hide yes)
			(effects
				(font
					(size 1 1)
					(thickness 0.15)
				)
				(justify mirror)
			)
		)
		(sheetname "/")
		(sheetfile "thunderbolt-to-10gbe-adapter.kicad_sch")
		(attr exclude_from_pos_files exclude_from_bom)
		(fp_circle
			(center 0 0)
			(end 1.24 0)
			(stroke
				(width 0.05)
				(type solid)
			)
			(fill no)
			(layer "B.CrtYd")
		)
		(fp_circle
			(center 0 0)
			(end 0.999 0)
			(stroke
				(width 0.15)
				(type solid)
			)
			(fill no)
			(layer "B.Fab")
		)
		(fp_text user "${REFERENCE}"
			(at -1.25 -4.603 0)
			(layer "B.Fab")
			(effects
				(font
					(size 0.7 0.7)
					(thickness 0.15)
				)
				(justify left bottom mirror)
			)
		)
		(fp_text user "Author: Antmicro"
			(at -1.25 -5.803 0)
			(layer "B.Fab")
			(effects
				(font
					(size 0.7 0.7)
					(thickness 0.15)
				)
				(justify left bottom mirror)
			)
		)
		(fp_text user "License: Apache-2.0"
			(at -1.25 -7.003 0)
			(layer "B.Fab")
			(effects
				(font
					(size 0.7 0.7)
					(thickness 0.15)
				)
				(justify left bottom mirror)
			)
		)
		(pad "" smd circle
			(at 0 0 180)
			(size 1 1)
			(layers "B.Cu" "B.Mask")
			(solder_mask_margin 0.5)
			(clearance 0.5)
		)
	)
	(footprint "antmicro-footprints:C_Pol_EIA-B"
		(layer "B.Cu")
		(at 117.8 142 -90)
		(property "Reference" "C6"
			(at -0.75 -2.7 90)
			(layer "B.SilkS")
			(effects
				(font
					(size 0.7 0.7)
					(thickness 0.15)
				)
				(justify left bottom mirror)
			)
		)
		(property "Value" "C_Pol_330u_6.3V_KEMET-T520-B"
			(at 0 -2.85 90)
			(layer "B.Fab")
			(effects
				(font
					(size 0.7 0.7)
					(thickness 0.15)
				)
				(justify left bottom mirror)
			)
		)
		(property "Datasheet" "https://www.kemet.com/en/us/capacitors/product/T520B337M006ATE040.html"
			(at 0 0 90)
			(layer "B.Fab")
			(hide yes)
			(effects
				(font
					(size 1.27 1.27)
					(thickness 0.15)
				)
				(justify mirror)
			)
		)
		(property "Description" "Tantalum Polymer Capacitor, KO-CAP®, 330 µF, ± 20%, 6.3 V, B, 0.04 ohm, 1411 [3528 Metric]"
			(at 0 0 90)
			(layer "B.Fab")
			(hide yes)
			(effects
				(font
					(size 1.27 1.27)
					(thickness 0.15)
				)
				(justify mirror)
			)
		)
		(property "Val" "330u"
			(at 0 0 270)
			(unlocked yes)
			(layer "B.Fab")
			(hide yes)
			(effects
				(font
					(size 1 1)
					(thickness 0.15)
				)
				(justify mirror)
			)
		)
		(property "MPN" "T520B337M006ATE040"
			(at 0 0 270)
			(unlocked yes)
			(layer "B.Fab")
			(hide yes)
			(effects
				(font
					(size 1 1)
					(thickness 0.15)
				)
				(justify mirror)
			)
		)
		(property "Manufacturer" "KEMET"
			(at 0 0 270)
			(unlocked yes)
			(layer "B.Fab")
			(hide yes)
			(effects
				(font
					(size 1 1)
					(thickness 0.15)
				)
				(justify mirror)
			)
		)
		(property "License" "Apache-2.0"
			(at 0 0 270)
			(unlocked yes)
			(layer "B.Fab")
			(hide yes)
			(effects
				(font
					(size 1 1)
					(thickness 0.15)
				)
				(justify mirror)
			)
		)
		(property "Author" "Antmicro"
			(at 0 0 270)
			(unlocked yes)
			(layer "B.Fab")
			(hide yes)
			(effects
				(font
					(size 1 1)
					(thickness 0.15)
				)
				(justify mirror)
			)
		)
		(property "Voltage" "6.3V"
			(at 0 0 270)
			(unlocked yes)
			(layer "B.Fab")
			(hide yes)
			(effects
				(font
					(size 1 1)
					(thickness 0.15)
				)
				(justify mirror)
			)
		)
		(property "Dielectric" "template_dielectric"
			(at 0 0 270)
			(unlocked yes)
			(layer "B.Fab")
			(hide yes)
			(effects
				(font
					(size 1 1)
					(thickness 0.15)
				)
				(justify mirror)
			)
		)
		(sheetname "/USB-C connector/")
		(sheetfile "USB-C_connector.kicad_sch")
		(attr smd dnp)
		(fp_line
			(start -2.521 1.676)
			(end -2.123 1.676)
			(stroke
				(width 0.15)
				(type solid)
			)
			(layer "B.SilkS")
		)
		(fp_line
			(start -1.8 1.6)
			(end 1.8 1.6)
			(stroke
				(width 0.15)
				(type solid)
			)
			(layer "B.SilkS")
		)
		(fp_line
			(start -2.325 1.475)
			(end -2.325 1.878)
			(stroke
				(width 0.15)
				(type solid)
			)
			(layer "B.SilkS")
		)
		(fp_line
			(start -1.8 1.3)
			(end -1.8 1.6)
			(stroke
				(width 0.15)
				(type solid)
			)
			(layer "B.SilkS")
		)
		(fp_line
			(start 1.8 1.3)
			(end 1.8 1.6)
			(stroke
				(width 0.15)
				(type solid)
			)
			(layer "B.SilkS")
		)
		(fp_line
			(start -1.8 -1.3)
			(end -1.8 -1.6)
			(stroke
				(width 0.15)
				(type solid)
			)
			(layer "B.SilkS")
		)
		(fp_line
			(start 1.8 -1.3)
			(end 1.8 -1.6)
			(stroke
				(width 0.15)
				(type solid)
			)
			(layer "B.SilkS")
		)
		(fp_line
			(start 1.8 -1.6)
			(end -1.8 -1.6)
			(stroke
				(width 0.15)
				(type solid)
			)
			(layer "B.SilkS")
		)
		(fp_line
			(start -1.97 1.75)
			(end -1.97 1.35)
			(stroke
				(width 0.05)
				(type solid)
			)
			(layer "B.CrtYd")
		)
		(fp_line
			(start 1.959 1.75)
			(end -1.97 1.75)
			(stroke
				(width 0.05)
				(type solid)
			)
			(layer "B.CrtYd")
		)
		(fp_line
			(start 1.959 1.75)
			(end 1.959 1.35)
			(stroke
				(width 0.05)
				(type solid)
			)
			(layer "B.CrtYd")
		)
		(fp_line
			(start -2.411 1.35)
			(end -2.41 -1.35)
			(stroke
				(width 0.05)
				(type solid)
			)
			(layer "B.CrtYd")
		)
		(fp_line
			(start -1.97 1.35)
			(end -2.41 1.35)
			(stroke
				(width 0.05)
				(type solid)
			)
			(layer "B.CrtYd")
		)
		(fp_line
			(start 2.399 1.35)
			(end 1.959 1.35)
			(stroke
				(width 0.05)
				(type solid)
			)
			(layer "B.CrtYd")
		)
		(fp_line
			(start 2.399 1.35)
			(end 2.4 -1.35)
			(stroke
				(width 0.05)
				(type solid)
			)
			(layer "B.CrtYd")
		)
		(fp_line
			(start -1.97 -1.35)
			(end -2.41 -1.35)
			(stroke
				(width 0.05)
				(type solid)
			)
			(layer "B.CrtYd")
		)
		(fp_line
			(start -1.97 -1.35)
			(end -1.97 -1.75)
			(stroke
				(width 0.05)
				(type solid)
			)
			(layer "B.CrtYd")
		)
		(fp_line
			(start 1.96 -1.35)
			(end 1.96 -1.75)
			(stroke
				(width 0.05)
				(type solid)
			)
			(layer "B.CrtYd")
		)
		(fp_line
			(start 2.4 -1.35)
			(end 1.96 -1.35)
			(stroke
				(width 0.05)
				(type solid)
			)
			(layer "B.CrtYd")
		)
		(fp_line
			(start 1.96 -1.75)
			(end -1.97 -1.75)
			(stroke
				(width 0.05)
				(type solid)
			)
			(layer "B.CrtYd")
		)
		(fp_line
			(start -1.7 -1.324)
			(end -1.551 -1.475)
			(stroke
				(width 0.15)
				(type solid)
			)
			(layer "B.Fab")
		)
		(fp_rect
			(start -1.72 1.5)
			(end 1.719 -1.499)
			(stroke
				(width 0.15)
				(type solid)
			)
			(fill no)
			(layer "B.Fab")
		)
		(fp_text user "License: Apache-2.0"
			(at -2.665 -5.65 90)
			(layer "B.Fab")
			(effects
				(font
					(size 0.7 0.7)
					(thickness 0.15)
				)
				(justify left bottom mirror)
			)
		)
		(fp_text user "Author: Antmicro"
			(at -2.665 -6.85 90)
			(layer "B.Fab")
			(effects
				(font
					(size 0.7 0.7)
					(thickness 0.15)
				)
				(justify left bottom mirror)
			)
		)
		(fp_text user "${REFERENCE}"
			(at -2.665 -4.45 90)
			(layer "B.Fab")
			(effects
				(font
					(size 0.7 0.7)
					(thickness 0.15)
				)
				(justify left bottom mirror)
			)
		)
		(pad "1" smd roundrect
			(at -1.551 0 270)
			(size 1.2 2.2)
			(layers "B.Cu" "B.Mask" "B.Paste")
			(roundrect_rratio 0.1)
			(net 53 "+5V_USB")
			(pintype "passive")
		)
		(pad "2" smd roundrect
			(at 1.55 0 270)
			(size 1.2 2.2)
			(layers "B.Cu" "B.Mask" "B.Paste")
			(roundrect_rratio 0.1)
			(net 23 "GND")
			(pintype "passive")
		)
	)
	(footprint "antmicro-footprints:C_0402_1005Metric"
		(layer "B.Cu")
		(at 149.331866 80.260117 180)
		(descr "Capacitor SMD 0402")
		(tags "capacitor SMD 0402")
		(property "Reference" "C260"
			(at -19.468135 -9.464883 0)
			(layer "B.SilkS")
			(effects
				(font
					(size 0.7 0.7)
					(thickness 0.15)
				)
				(justify mirror)
			)
		)
		(property "Value" "C_1u_25V_0402"
			(at -1.022927 -2.155213 0)
			(layer "B.Fab")
			(effects
				(font
					(size 0.7 0.7)
					(thickness 0.15)
				)
				(justify left bottom mirror)
			)
		)
		(property "Datasheet" "https://www.murata.com/products/productdetail?partno=GRM155R61E105KE11%23"
			(at 0 0 0)
			(layer "B.Fab")
			(hide yes)
			(effects
				(font
					(size 1.27 1.27)
					(thickness 0.15)
				)
				(justify mirror)
			)
		)
		(property "Description" "SMD Multilayer Ceramic Capacitor, 1 µF, 25 V, 0402 [1005 Metric], ± 10%, X5R, GRM Series"
			(at 0 0 0)
			(layer "B.Fab")
			(hide yes)
			(effects
				(font
					(size 1.27 1.27)
					(thickness 0.15)
				)
				(justify mirror)
			)
		)
		(property "MPN" "GRM155R61E105KE11J"
			(at 0 0 180)
			(unlocked yes)
			(layer "B.Fab")
			(hide yes)
			(effects
				(font
					(size 1 1)
					(thickness 0.15)
				)
				(justify mirror)
			)
		)
		(property "Manufacturer" "Murata"
			(at 0 0 180)
			(unlocked yes)
			(layer "B.Fab")
			(hide yes)
			(effects
				(font
					(size 1 1)
					(thickness 0.15)
				)
				(justify mirror)
			)
		)
		(property "License" "Apache-2.0"
			(at 0 0 180)
			(unlocked yes)
			(layer "B.Fab")
			(hide yes)
			(effects
				(font
					(size 1 1)
					(thickness 0.15)
				)
				(justify mirror)
			)
		)
		(property "Author" "Antmicro"
			(at 0 0 180)
			(unlocked yes)
			(layer "B.Fab")
			(hide yes)
			(effects
				(font
					(size 1 1)
					(thickness 0.15)
				)
				(justify mirror)
			)
		)
		(property "Val" "1u"
			(at 0 0 180)
			(unlocked yes)
			(layer "B.Fab")
			(hide yes)
			(effects
				(font
					(size 1 1)
					(thickness 0.15)
				)
				(justify mirror)
			)
		)
		(property "Voltage" "25V"
			(at 0 0 180)
			(unlocked yes)
			(layer "B.Fab")
			(hide yes)
			(effects
				(font
					(size 1 1)
					(thickness 0.15)
				)
				(justify mirror)
			)
		)
		(property "Dielectric" "X5R"
			(at 0 0 180)
			(unlocked yes)
			(layer "B.Fab")
			(hide yes)
			(effects
				(font
					(size 1 1)
					(thickness 0.15)
				)
				(justify mirror)
			)
		)
		(sheetname "/X710-AT2 power/")
		(sheetfile "x710-at2-power.kicad_sch")
		(attr smd)
		(fp_rect
			(start -0.925 0.47)
			(end 0.925 -0.47)
			(stroke
				(width 0.05)
				(type default)
			)
			(fill no)
			(layer "B.CrtYd")
		)
		(fp_line
			(start 0.504 0.25)
			(end 0.504 -0.248)
			(stroke
				(width 0.15)
				(type solid)
			)
			(layer "B.Fab")
		)
		(fp_line
			(start 0.504 -0.248)
			(end -0.494 -0.248)
			(stroke
				(width 0.15)
				(type solid)
			)
			(layer "B.Fab")
		)
		(fp_line
			(start -0.494 0.25)
			(end 0.504 0.25)
			(stroke
				(width 0.15)
				(type solid)
			)
			(layer "B.Fab")
		)
		(fp_line
			(start -0.494 -0.248)
			(end -0.494 0.25)
			(stroke
				(width 0.15)
				(type solid)
			)
			(layer "B.Fab")
		)
		(fp_text user "${REFERENCE}"
			(at -0.939 -4.599 0)
			(layer "B.Fab")
			(effects
				(font
					(size 0.7 0.7)
					(thickness 0.15)
				)
				(justify left bottom mirror)
			)
		)
		(fp_text user "License: Apache-2.0"
			(at -0.939 -5.799 0)
			(layer "B.Fab")
			(effects
				(font
					(size 0.7 0.7)
					(thickness 0.15)
				)
				(justify left bottom mirror)
			)
		)
		(fp_text user "Author: Antmicro"
			(at -0.939 -3.399 0)
			(layer "B.Fab")
			(effects
				(font
					(size 0.7 0.7)
					(thickness 0.15)
				)
				(justify left bottom mirror)
			)
		)
		(pad "1" smd roundrect
			(at -0.48 0 180)
			(size 0.59 0.64)
			(layers "B.Cu" "B.Mask" "B.Paste")
			(roundrect_rratio 0.25)
			(net 23 "GND")
			(pintype "passive")
		)
		(pad "2" smd roundrect
			(at 0.48 0 180)
			(size 0.59 0.64)
			(layers "B.Cu" "B.Mask" "B.Paste")
			(roundrect_rratio 0.25)
			(net 9 "VCCD")
			(pintype "passive")
		)
	)
)
